# SI test board — symbol library table
(sym_lib_table
  (lib (name "si-simulation-test-board")(type "KiCad")(uri "${KIPRJMOD}/lib/si-simulation-test-board.kicad_sym")(options "")(descr ""))
)
